(kicad_pcb
	(version 20260206)
	(generator "pcbnew")
	(generator_version "10.0")
	(general
		(thickness 1.6)
		(legacy_teardrops no)
	)
	(paper "A4")
	(title_block
		(title "04192023_DAF0TMB3IC0_F0TG_MB_C_brd_V02_OCP.brd")
		(comment 1 "Grand Teton / footprints 5029-5035 of 8354")
	)
	(layers
		(0 "F.Cu" signal "TOP")
		(4 "In1.Cu" signal "GND")
		(6 "In2.Cu" signal "IN1")
		(8 "In3.Cu" signal "GND1")
		(10 "In4.Cu" signal "IN2")
		(12 "In5.Cu" signal "GND2")
		(14 "In6.Cu" signal "IN3")
		(16 "In7.Cu" signal "GND3")
		(18 "In8.Cu" signal "VCC")
		(20 "In9.Cu" signal "VCC1")
		(22 "In10.Cu" signal "GND4")
		(24 "In11.Cu" signal "IN4")
		(26 "In12.Cu" signal "GND5")
		(28 "In13.Cu" signal "IN5")
		(30 "In14.Cu" signal "GND6")
		(32 "In15.Cu" signal "IN6")
		(34 "In16.Cu" signal "GND7")
		(2 "B.Cu" signal "BOTTOM")
		(9 "F.Adhes" user "F.Adhesive")
		(11 "B.Adhes" user "B.Adhesive")
		(13 "F.Paste" user "Package Geometry/Pastemask Top")
		(15 "B.Paste" user "Package Geometry/Pastemask Bottom")
		(5 "F.SilkS" user "Ref Des/Silkscreen Top")
		(7 "B.SilkS" user "Ref Des/Silkscreen Bottom")
		(1 "F.Mask" user "Board Geometry/Soldermask Top")
		(3 "B.Mask" user "Board Geometry/Soldermask Bottom")
		(17 "Dwgs.User" user "User.Drawings")
		(19 "Cmts.User" user "User.Comments")
		(21 "Eco1.User" user "User.Eco1")
		(23 "Eco2.User" user "User.Eco2")
		(25 "Edge.Cuts" user "Board Geometry/Outline")
		(27 "Margin" user)
		(31 "F.CrtYd" user "Package Geometry/Place Bound Top")
		(29 "B.CrtYd" user "Package Geometry/Place Bound Bottom")
		(35 "F.Fab" user "Ref Des/Assembly Top")
		(33 "B.Fab" user "Ref Des/Assembly Bottom")
	)
	(footprint ""
		(layer "B.Cu")
		(at 161.419032 -390.560052 90)
		(property "Reference" "C420"
			(at 0 0 90)
			(layer "B.SilkS")
			(hide yes)
			(effects
				(font
					(size 1.27 1.27)
				)
				(justify mirror)
			)
		)
		(property "Value" ""
			(at 0 0 90)
			(layer "B.Fab")
			(effects
				(font
					(size 1.27 1.27)
				)
				(justify mirror)
			)
		)
		(duplicate_pad_numbers_are_jumpers no)
		(fp_line
			(start 0.7874 -0.4064)
			(end -0.7874 -0.4064)
			(stroke
				(width 0.1524)
				(type default)
			)
			(layer "B.SilkS")
		)
		(fp_line
			(start -0.7874 -0.4064)
			(end -0.7874 0.4064)
			(stroke
				(width 0.1524)
				(type default)
			)
			(layer "B.SilkS")
		)
		(fp_line
			(start 0.7874 0.4064)
			(end 0.7874 -0.4064)
			(stroke
				(width 0.1524)
				(type default)
			)
			(layer "B.SilkS")
		)
		(fp_line
			(start -0.7874 0.4064)
			(end 0.7874 0.4064)
			(stroke
				(width 0.1524)
				(type default)
			)
			(layer "B.SilkS")
		)
		(fp_line
			(start 0.67945 -0.305054)
			(end 0.12065 -0.305054)
			(stroke
				(width 0.1)
				(type default)
			)
			(layer "B.Fab")
		)
		(fp_line
			(start 0.12065 -0.305054)
			(end 0.12065 -0.2794)
			(stroke
				(width 0.1)
				(type default)
			)
			(layer "B.Fab")
		)
		(fp_line
			(start -0.12065 -0.3048)
			(end -0.67945 -0.3048)
			(stroke
				(width 0.1)
				(type default)
			)
			(layer "B.Fab")
		)
		(fp_line
			(start -0.67945 -0.3048)
			(end -0.67945 0.3048)
			(stroke
				(width 0.1)
				(type default)
			)
			(layer "B.Fab")
		)
		(fp_line
			(start 0.12065 -0.2794)
			(end -0.12065 -0.2794)
			(stroke
				(width 0.1)
				(type default)
			)
			(layer "B.Fab")
		)
		(fp_line
			(start -0.12065 -0.2794)
			(end -0.12065 -0.3048)
			(stroke
				(width 0.1)
				(type default)
			)
			(layer "B.Fab")
		)
		(fp_line
			(start 0.12065 0.2794)
			(end 0.12065 0.3048)
			(stroke
				(width 0.1)
				(type default)
			)
			(layer "B.Fab")
		)
		(fp_line
			(start -0.120396 0.2794)
			(end 0.12065 0.2794)
			(stroke
				(width 0.1)
				(type default)
			)
			(layer "B.Fab")
		)
		(fp_line
			(start 0.67945 0.3048)
			(end 0.67945 -0.305054)
			(stroke
				(width 0.1)
				(type default)
			)
			(layer "B.Fab")
		)
		(fp_line
			(start 0.12065 0.3048)
			(end 0.67945 0.3048)
			(stroke
				(width 0.1)
				(type default)
			)
			(layer "B.Fab")
		)
		(fp_line
			(start -0.120396 0.3048)
			(end -0.120396 0.2794)
			(stroke
				(width 0.1)
				(type default)
			)
			(layer "B.Fab")
		)
		(fp_line
			(start -0.67945 0.3048)
			(end -0.120396 0.3048)
			(stroke
				(width 0.1)
				(type default)
			)
			(layer "B.Fab")
		)
		(pad "1" smd circle
			(at 0.40005 0 270)
			(size 0 0)
			(layers "B.Cu" "B.Mask" "B.Paste")
			(net "P0V9_CPU1_RT2_2A")
		)
		(pad "2" smd circle
			(at -0.40005 0 270)
			(size 0 0)
			(layers "B.Cu" "B.Mask" "B.Paste")
			(net "GND")
		)
	)
	(footprint ""
		(layer "B.Cu")
		(at 165.58514 -9.013444 90)
		(property "Reference" "R65"
			(at 0 0 90)
			(layer "B.SilkS")
			(hide yes)
			(effects
				(font
					(size 1.27 1.27)
				)
				(justify mirror)
			)
		)
		(property "Value" ""
			(at 0 0 90)
			(layer "B.Fab")
			(effects
				(font
					(size 1.27 1.27)
				)
				(justify mirror)
			)
		)
		(duplicate_pad_numbers_are_jumpers no)
		(fp_line
			(start 0.7874 -0.4064)
			(end -0.7874 -0.4064)
			(stroke
				(width 0.1524)
				(type default)
			)
			(layer "B.SilkS")
		)
		(fp_line
			(start -0.7874 -0.4064)
			(end -0.7874 0.4064)
			(stroke
				(width 0.1524)
				(type default)
			)
			(layer "B.SilkS")
		)
		(fp_line
			(start 0.7874 0.4064)
			(end 0.7874 -0.4064)
			(stroke
				(width 0.1524)
				(type default)
			)
			(layer "B.SilkS")
		)
		(fp_line
			(start -0.7874 0.4064)
			(end 0.7874 0.4064)
			(stroke
				(width 0.1524)
				(type default)
			)
			(layer "B.SilkS")
		)
		(fp_line
			(start 0.67945 -0.305054)
			(end 0.12065 -0.305054)
			(stroke
				(width 0.1)
				(type default)
			)
			(layer "B.Fab")
		)
		(fp_line
			(start 0.12065 -0.305054)
			(end 0.12065 -0.2794)
			(stroke
				(width 0.1)
				(type default)
			)
			(layer "B.Fab")
		)
		(fp_line
			(start -0.12065 -0.3048)
			(end -0.67945 -0.3048)
			(stroke
				(width 0.1)
				(type default)
			)
			(layer "B.Fab")
		)
		(fp_line
			(start -0.67945 -0.3048)
			(end -0.67945 0.3048)
			(stroke
				(width 0.1)
				(type default)
			)
			(layer "B.Fab")
		)
		(fp_line
			(start 0.12065 -0.2794)
			(end -0.12065 -0.2794)
			(stroke
				(width 0.1)
				(type default)
			)
			(layer "B.Fab")
		)
		(fp_line
			(start -0.12065 -0.2794)
			(end -0.12065 -0.3048)
			(stroke
				(width 0.1)
				(type default)
			)
			(layer "B.Fab")
		)
		(fp_line
			(start 0.12065 0.2794)
			(end 0.12065 0.3048)
			(stroke
				(width 0.1)
				(type default)
			)
			(layer "B.Fab")
		)
		(fp_line
			(start -0.120396 0.2794)
			(end 0.12065 0.2794)
			(stroke
				(width 0.1)
				(type default)
			)
			(layer "B.Fab")
		)
		(fp_line
			(start 0.67945 0.3048)
			(end 0.67945 -0.305054)
			(stroke
				(width 0.1)
				(type default)
			)
			(layer "B.Fab")
		)
		(fp_line
			(start 0.12065 0.3048)
			(end 0.67945 0.3048)
			(stroke
				(width 0.1)
				(type default)
			)
			(layer "B.Fab")
		)
		(fp_line
			(start -0.120396 0.3048)
			(end -0.120396 0.2794)
			(stroke
				(width 0.1)
				(type default)
			)
			(layer "B.Fab")
		)
		(fp_line
			(start -0.67945 0.3048)
			(end -0.120396 0.3048)
			(stroke
				(width 0.1)
				(type default)
			)
			(layer "B.Fab")
		)
		(pad "1" smd circle
			(at 0.40005 0 270)
			(size 0 0)
			(layers "B.Cu" "B.Mask" "B.Paste")
			(net "SMB_PCIE0_3V3AUX_SCL")
		)
		(pad "2" smd circle
			(at -0.40005 0 270)
			(size 0 0)
			(layers "B.Cu" "B.Mask" "B.Paste")
			(net "SMB_PCIE0_3V3AUX_SCL_R")
		)
	)
	(footprint ""
		(layer "B.Cu")
		(at 428.98695 -32.197548 180)
		(property "Reference" "R1358"
			(at 0 0 0)
			(layer "B.SilkS")
			(hide yes)
			(effects
				(font
					(size 1.27 1.27)
				)
				(justify mirror)
			)
		)
		(property "Value" ""
			(at 0 0 0)
			(layer "B.Fab")
			(effects
				(font
					(size 1.27 1.27)
				)
				(justify mirror)
			)
		)
		(duplicate_pad_numbers_are_jumpers no)
		(fp_line
			(start 0.7874 0.4064)
			(end 0.7874 -0.4064)
			(stroke
				(width 0.1524)
				(type default)
			)
			(layer "B.SilkS")
		)
		(fp_line
			(start 0.7874 -0.4064)
			(end -0.7874 -0.4064)
			(stroke
				(width 0.1524)
				(type default)
			)
			(layer "B.SilkS")
		)
		(fp_line
			(start -0.7874 0.4064)
			(end 0.7874 0.4064)
			(stroke
				(width 0.1524)
				(type default)
			)
			(layer "B.SilkS")
		)
		(fp_line
			(start -0.7874 -0.4064)
			(end -0.7874 0.4064)
			(stroke
				(width 0.1524)
				(type default)
			)
			(layer "B.SilkS")
		)
		(fp_line
			(start 0.67945 0.3048)
			(end 0.67945 -0.305054)
			(stroke
				(width 0.1)
				(type default)
			)
			(layer "B.Fab")
		)
		(fp_line
			(start 0.67945 -0.305054)
			(end 0.12065 -0.305054)
			(stroke
				(width 0.1)
				(type default)
			)
			(layer "B.Fab")
		)
		(fp_line
			(start 0.12065 0.3048)
			(end 0.67945 0.3048)
			(stroke
				(width 0.1)
				(type default)
			)
			(layer "B.Fab")
		)
		(fp_line
			(start 0.12065 0.2794)
			(end 0.12065 0.3048)
			(stroke
				(width 0.1)
				(type default)
			)
			(layer "B.Fab")
		)
		(fp_line
			(start 0.12065 -0.2794)
			(end -0.12065 -0.2794)
			(stroke
				(width 0.1)
				(type default)
			)
			(layer "B.Fab")
		)
		(fp_line
			(start 0.12065 -0.305054)
			(end 0.12065 -0.2794)
			(stroke
				(width 0.1)
				(type default)
			)
			(layer "B.Fab")
		)
		(fp_line
			(start -0.120396 0.3048)
			(end -0.120396 0.2794)
			(stroke
				(width 0.1)
				(type default)
			)
			(layer "B.Fab")
		)
		(fp_line
			(start -0.120396 0.2794)
			(end 0.12065 0.2794)
			(stroke
				(width 0.1)
				(type default)
			)
			(layer "B.Fab")
		)
		(fp_line
			(start -0.12065 -0.2794)
			(end -0.12065 -0.3048)
			(stroke
				(width 0.1)
				(type default)
			)
			(layer "B.Fab")
		)
		(fp_line
			(start -0.12065 -0.3048)
			(end -0.67945 -0.3048)
			(stroke
				(width 0.1)
				(type default)
			)
			(layer "B.Fab")
		)
		(fp_line
			(start -0.67945 0.3048)
			(end -0.120396 0.3048)
			(stroke
				(width 0.1)
				(type default)
			)
			(layer "B.Fab")
		)
		(fp_line
			(start -0.67945 -0.3048)
			(end -0.67945 0.3048)
			(stroke
				(width 0.1)
				(type default)
			)
			(layer "B.Fab")
		)
		(pad "1" smd circle
			(at 0.40005 0)
			(size 0 0)
			(layers "B.Cu" "B.Mask" "B.Paste")
			(net "P1V8_AUX")
		)
		(pad "2" smd circle
			(at -0.40005 0)
			(size 0 0)
			(layers "B.Cu" "B.Mask" "B.Paste")
			(net "FM_PASSWORD_CLEAR_N")
		)
	)
	(footprint ""
		(layer "B.Cu")
		(at 353.485958 -272.284952)
		(property "Reference" "C2250"
			(at 0 0 0)
			(layer "B.SilkS")
			(hide yes)
			(effects
				(font
					(size 1.27 1.27)
				)
				(justify mirror)
			)
		)
		(property "Value" ""
			(at 0 0 0)
			(layer "B.Fab")
			(effects
				(font
					(size 1.27 1.27)
				)
				(justify mirror)
			)
		)
		(duplicate_pad_numbers_are_jumpers no)
		(fp_line
			(start -0.7874 -0.4064)
			(end -0.7874 0.4064)
			(stroke
				(width 0.1524)
				(type default)
			)
			(layer "B.SilkS")
		)
		(fp_line
			(start -0.7874 0.4064)
			(end 0.7874 0.4064)
			(stroke
				(width 0.1524)
				(type default)
			)
			(layer "B.SilkS")
		)
		(fp_line
			(start 0.7874 -0.4064)
			(end -0.7874 -0.4064)
			(stroke
				(width 0.1524)
				(type default)
			)
			(layer "B.SilkS")
		)
		(fp_line
			(start 0.7874 0.4064)
			(end 0.7874 -0.4064)
			(stroke
				(width 0.1524)
				(type default)
			)
			(layer "B.SilkS")
		)
		(fp_line
			(start -0.67945 -0.3048)
			(end -0.67945 0.3048)
			(stroke
				(width 0.1)
				(type default)
			)
			(layer "B.Fab")
		)
		(fp_line
			(start -0.67945 0.3048)
			(end -0.120396 0.3048)
			(stroke
				(width 0.1)
				(type default)
			)
			(layer "B.Fab")
		)
		(fp_line
			(start -0.12065 -0.3048)
			(end -0.67945 -0.3048)
			(stroke
				(width 0.1)
				(type default)
			)
			(layer "B.Fab")
		)
		(fp_line
			(start -0.12065 -0.2794)
			(end -0.12065 -0.3048)
			(stroke
				(width 0.1)
				(type default)
			)
			(layer "B.Fab")
		)
		(fp_line
			(start -0.120396 0.2794)
			(end 0.12065 0.2794)
			(stroke
				(width 0.1)
				(type default)
			)
			(layer "B.Fab")
		)
		(fp_line
			(start -0.120396 0.3048)
			(end -0.120396 0.2794)
			(stroke
				(width 0.1)
				(type default)
			)
			(layer "B.Fab")
		)
		(fp_line
			(start 0.12065 -0.305054)
			(end 0.12065 -0.2794)
			(stroke
				(width 0.1)
				(type default)
			)
			(layer "B.Fab")
		)
		(fp_line
			(start 0.12065 -0.2794)
			(end -0.12065 -0.2794)
			(stroke
				(width 0.1)
				(type default)
			)
			(layer "B.Fab")
		)
		(fp_line
			(start 0.12065 0.2794)
			(end 0.12065 0.3048)
			(stroke
				(width 0.1)
				(type default)
			)
			(layer "B.Fab")
		)
		(fp_line
			(start 0.12065 0.3048)
			(end 0.67945 0.3048)
			(stroke
				(width 0.1)
				(type default)
			)
			(layer "B.Fab")
		)
		(fp_line
			(start 0.67945 -0.305054)
			(end 0.12065 -0.305054)
			(stroke
				(width 0.1)
				(type default)
			)
			(layer "B.Fab")
		)
		(fp_line
			(start 0.67945 0.3048)
			(end 0.67945 -0.305054)
			(stroke
				(width 0.1)
				(type default)
			)
			(layer "B.Fab")
		)
		(pad "1" smd circle
			(at 0.40005 0 180)
			(size 0 0)
			(layers "B.Cu" "B.Mask" "B.Paste")
			(net "PVDDCR_CPU1_P0")
		)
		(pad "2" smd circle
			(at -0.40005 0 180)
			(size 0 0)
			(layers "B.Cu" "B.Mask" "B.Paste")
			(net "GND")
		)
	)
	(footprint ""
		(layer "B.Cu")
		(at 353.136454 -248.47931)
		(property "Reference" "C2178"
			(at 0 0 0)
			(layer "B.SilkS")
			(hide yes)
			(effects
				(font
					(size 1.27 1.27)
				)
				(justify mirror)
			)
		)
		(property "Value" ""
			(at 0 0 0)
			(layer "B.Fab")
			(effects
				(font
					(size 1.27 1.27)
				)
				(justify mirror)
			)
		)
		(duplicate_pad_numbers_are_jumpers no)
		(fp_line
			(start -0.7874 -0.4064)
			(end -0.7874 0.4064)
			(stroke
				(width 0.1524)
				(type default)
			)
			(layer "B.SilkS")
		)
		(fp_line
			(start -0.7874 0.4064)
			(end 0.7874 0.4064)
			(stroke
				(width 0.1524)
				(type default)
			)
			(layer "B.SilkS")
		)
		(fp_line
			(start 0.7874 -0.4064)
			(end -0.7874 -0.4064)
			(stroke
				(width 0.1524)
				(type default)
			)
			(layer "B.SilkS")
		)
		(fp_line
			(start 0.7874 0.4064)
			(end 0.7874 -0.4064)
			(stroke
				(width 0.1524)
				(type default)
			)
			(layer "B.SilkS")
		)
		(fp_line
			(start -0.67945 -0.3048)
			(end -0.67945 0.3048)
			(stroke
				(width 0.1)
				(type default)
			)
			(layer "B.Fab")
		)
		(fp_line
			(start -0.67945 0.3048)
			(end -0.120396 0.3048)
			(stroke
				(width 0.1)
				(type default)
			)
			(layer "B.Fab")
		)
		(fp_line
			(start -0.12065 -0.3048)
			(end -0.67945 -0.3048)
			(stroke
				(width 0.1)
				(type default)
			)
			(layer "B.Fab")
		)
		(fp_line
			(start -0.12065 -0.2794)
			(end -0.12065 -0.3048)
			(stroke
				(width 0.1)
				(type default)
			)
			(layer "B.Fab")
		)
		(fp_line
			(start -0.120396 0.2794)
			(end 0.12065 0.2794)
			(stroke
				(width 0.1)
				(type default)
			)
			(layer "B.Fab")
		)
		(fp_line
			(start -0.120396 0.3048)
			(end -0.120396 0.2794)
			(stroke
				(width 0.1)
				(type default)
			)
			(layer "B.Fab")
		)
		(fp_line
			(start 0.12065 -0.305054)
			(end 0.12065 -0.2794)
			(stroke
				(width 0.1)
				(type default)
			)
			(layer "B.Fab")
		)
		(fp_line
			(start 0.12065 -0.2794)
			(end -0.12065 -0.2794)
			(stroke
				(width 0.1)
				(type default)
			)
			(layer "B.Fab")
		)
		(fp_line
			(start 0.12065 0.2794)
			(end 0.12065 0.3048)
			(stroke
				(width 0.1)
				(type default)
			)
			(layer "B.Fab")
		)
		(fp_line
			(start 0.12065 0.3048)
			(end 0.67945 0.3048)
			(stroke
				(width 0.1)
				(type default)
			)
			(layer "B.Fab")
		)
		(fp_line
			(start 0.67945 -0.305054)
			(end 0.12065 -0.305054)
			(stroke
				(width 0.1)
				(type default)
			)
			(layer "B.Fab")
		)
		(fp_line
			(start 0.67945 0.3048)
			(end 0.67945 -0.305054)
			(stroke
				(width 0.1)
				(type default)
			)
			(layer "B.Fab")
		)
		(pad "1" smd circle
			(at 0.40005 0 180)
			(size 0 0)
			(layers "B.Cu" "B.Mask" "B.Paste")
			(net "PVDDCR_CPU0_P0")
		)
		(pad "2" smd circle
			(at -0.40005 0 180)
			(size 0 0)
			(layers "B.Cu" "B.Mask" "B.Paste")
			(net "GND")
		)
	)
	(footprint ""
		(layer "B.Cu")
		(at 79.700628 -385.50088 -90)
		(property "Reference" "C293"
			(at 0 0 90)
			(layer "B.SilkS")
			(hide yes)
			(effects
				(font
					(size 1.27 1.27)
				)
				(justify mirror)
			)
		)
		(property "Value" ""
			(at 0 0 90)
			(layer "B.Fab")
			(effects
				(font
					(size 1.27 1.27)
				)
				(justify mirror)
			)
		)
		(duplicate_pad_numbers_are_jumpers no)
		(fp_line
			(start -0.299974 0.150114)
			(end 0.299974 0.150114)
			(stroke
				(width 0.1)
				(type default)
			)
			(layer "B.Fab")
		)
		(fp_line
			(start 0.299974 0.150114)
			(end 0.299974 -0.150114)
			(stroke
				(width 0.1)
				(type default)
			)
			(layer "B.Fab")
		)
		(fp_line
			(start -0.299974 -0.150114)
			(end -0.299974 0.150114)
			(stroke
				(width 0.1)
				(type default)
			)
			(layer "B.Fab")
		)
		(fp_line
			(start 0.299974 -0.150114)
			(end -0.299974 -0.150114)
			(stroke
				(width 0.1)
				(type default)
			)
			(layer "B.Fab")
		)
		(pad "1" smd rect
			(at 0.2667 0 90)
			(size 0.3048 0.381)
			(layers "B.Cu" "B.Mask" "B.Paste")
			(net "P0V9_CPU1_RT1_2A")
		)
		(pad "2" smd rect
			(at -0.2667 0 90)
			(size 0.3048 0.381)
			(layers "B.Cu" "B.Mask" "B.Paste")
			(net "GND")
		)
	)
	(footprint ""
		(layer "B.Cu")
		(at 148.122386 -314.47105)
		(property "Reference" "C236"
			(at 0 0 0)
			(layer "B.SilkS")
			(hide yes)
			(effects
				(font
					(size 1.27 1.27)
				)
				(justify mirror)
			)
		)
		(property "Value" ""
			(at 0 0 0)
			(layer "B.Fab")
			(effects
				(font
					(size 1.27 1.27)
				)
				(justify mirror)
			)
		)
		(duplicate_pad_numbers_are_jumpers no)
		(fp_line
			(start -0.7874 -0.4064)
			(end -0.7874 0.4064)
			(stroke
				(width 0.1524)
				(type default)
			)
			(layer "B.SilkS")
		)
		(fp_line
			(start -0.7874 0.4064)
			(end 0.7874 0.4064)
			(stroke
				(width 0.1524)
				(type default)
			)
			(layer "B.SilkS")
		)
		(fp_line
			(start 0.7874 -0.4064)
			(end -0.7874 -0.4064)
			(stroke
				(width 0.1524)
				(type default)
			)
			(layer "B.SilkS")
		)
		(fp_line
			(start 0.7874 0.4064)
			(end 0.7874 -0.4064)
			(stroke
				(width 0.1524)
				(type default)
			)
			(layer "B.SilkS")
		)
		(fp_line
			(start -0.67945 -0.3048)
			(end -0.67945 0.3048)
			(stroke
				(width 0.1)
				(type default)
			)
			(layer "B.Fab")
		)
		(fp_line
			(start -0.67945 0.3048)
			(end -0.120396 0.3048)
			(stroke
				(width 0.1)
				(type default)
			)
			(layer "B.Fab")
		)
		(fp_line
			(start -0.12065 -0.3048)
			(end -0.67945 -0.3048)
			(stroke
				(width 0.1)
				(type default)
			)
			(layer "B.Fab")
		)
		(fp_line
			(start -0.12065 -0.2794)
			(end -0.12065 -0.3048)
			(stroke
				(width 0.1)
				(type default)
			)
			(layer "B.Fab")
		)
		(fp_line
			(start -0.120396 0.2794)
			(end 0.12065 0.2794)
			(stroke
				(width 0.1)
				(type default)
			)
			(layer "B.Fab")
		)
		(fp_line
			(start -0.120396 0.3048)
			(end -0.120396 0.2794)
			(stroke
				(width 0.1)
				(type default)
			)
			(layer "B.Fab")
		)
		(fp_line
			(start 0.12065 -0.305054)
			(end 0.12065 -0.2794)
			(stroke
				(width 0.1)
				(type default)
			)
			(layer "B.Fab")
		)
		(fp_line
			(start 0.12065 -0.2794)
			(end -0.12065 -0.2794)
			(stroke
				(width 0.1)
				(type default)
			)
			(layer "B.Fab")
		)
		(fp_line
			(start 0.12065 0.2794)
			(end 0.12065 0.3048)
			(stroke
				(width 0.1)
				(type default)
			)
			(layer "B.Fab")
		)
		(fp_line
			(start 0.12065 0.3048)
			(end 0.67945 0.3048)
			(stroke
				(width 0.1)
				(type default)
			)
			(layer "B.Fab")
		)
		(fp_line
			(start 0.67945 -0.305054)
			(end 0.12065 -0.305054)
			(stroke
				(width 0.1)
				(type default)
			)
			(layer "B.Fab")
		)
		(fp_line
			(start 0.67945 0.3048)
			(end 0.67945 -0.305054)
			(stroke
				(width 0.1)
				(type default)
			)
			(layer "B.Fab")
		)
		(pad "1" smd circle
			(at 0.40005 0 180)
			(size 0 0)
			(layers "B.Cu" "B.Mask" "B.Paste")
			(net "XTAL_CPU1_X48M_X1")
		)
		(pad "2" smd circle
			(at -0.40005 0 180)
			(size 0 0)
			(layers "B.Cu" "B.Mask" "B.Paste")
			(net "GND")
		)
	)
)
